# T6G (Grand Teton) — schematic netlist excerpt (pin names and nets, part order shuffled) for the footprints in the layout excerpt that follows; sources: Cadence DE-HDL packaged netlist, KiCad conversion of 04192023_DAF0TMB3IC0_F0TG_MB_C_brd_V02_OCP.brd

C717  Q_CAP_DIFFBUS  DIFF BUS_0.22UF 6.3V 20% X6S  pkg C0201  page 66 : \1\ = P5E_CPU1_P1_TX_C_DP<12> ; \2\ = P5E_CPU1_P1_TX_DP<12>
R732  Q_RES  0 5% CHIP  pkg 0201LF  page 331 : A = RST_RT_CPU1_P1_RESET_N ; B = RST_RT_CPU1_P1_RESET_R_N
PC6003  Q_CAP  0.1UF 25V 10% X7R  pkg 0402  page 208 : A = P12V_AUX ; B = GND

(kicad_pcb
	(version 20260206)
	(generator "pcbnew")
	(generator_version "10.0")
	(general
		(thickness 1.6)
		(legacy_teardrops no)
	)
	(paper "A4")
	(title_block
		(title "04192023_DAF0TMB3IC0_F0TG_MB_C_brd_V02_OCP.brd")
		(comment 1 "Grand Teton / footprints 2751-2753 of 8354")
	)
	(layers
		(0 "F.Cu" signal "TOP")
		(4 "In1.Cu" signal "GND")
		(6 "In2.Cu" signal "IN1")
		(8 "In3.Cu" signal "GND1")
		(10 "In4.Cu" signal "IN2")
		(12 "In5.Cu" signal "GND2")
		(14 "In6.Cu" signal "IN3")
		(16 "In7.Cu" signal "GND3")
		(18 "In8.Cu" signal "VCC")
		(20 "In9.Cu" signal "VCC1")
		(22 "In10.Cu" signal "GND4")
		(24 "In11.Cu" signal "IN4")
		(26 "In12.Cu" signal "GND5")
		(28 "In13.Cu" signal "IN5")
		(30 "In14.Cu" signal "GND6")
		(32 "In15.Cu" signal "IN6")
		(34 "In16.Cu" signal "GND7")
		(2 "B.Cu" signal "BOTTOM")
		(9 "F.Adhes" user "F.Adhesive")
		(11 "B.Adhes" user "B.Adhesive")
		(13 "F.Paste" user "Package Geometry/Pastemask Top")
		(15 "B.Paste" user "Package Geometry/Pastemask Bottom")
		(5 "F.SilkS" user "Ref Des/Silkscreen Top")
		(7 "B.SilkS" user "Ref Des/Silkscreen Bottom")
		(1 "F.Mask" user "Board Geometry/Soldermask Top")
		(3 "B.Mask" user "Board Geometry/Soldermask Bottom")
		(17 "Dwgs.User" user "User.Drawings")
		(19 "Cmts.User" user "User.Comments")
		(21 "Eco1.User" user "User.Eco1")
		(23 "Eco2.User" user "User.Eco2")
		(25 "Edge.Cuts" user "Board Geometry/Outline")
		(27 "Margin" user)
		(31 "F.CrtYd" user "Package Geometry/Place Bound Top")
		(29 "B.CrtYd" user "Package Geometry/Place Bound Bottom")
		(35 "F.Fab" user "Ref Des/Assembly Top")
		(33 "B.Fab" user "Ref Des/Assembly Bottom")
	)
	(footprint ""
		(layer "F.Cu")
		(at 97.640902 -370.57203 -90)
		(property "Reference" "C717"
			(at 0 0 270)
			(layer "F.SilkS")
			(hide yes)
			(effects
				(font
					(size 1.27 1.27)
				)
			)
		)
		(property "Value" ""
			(at 0 0 270)
			(layer "F.Fab")
			(effects
				(font
					(size 1.27 1.27)
				)
			)
		)
		(duplicate_pad_numbers_are_jumpers no)
		(fp_line
			(start -0.299974 0.150114)
			(end -0.299974 -0.150114)
			(stroke
				(width 0.1)
				(type default)
			)
			(layer "F.Fab")
		)
		(fp_line
			(start 0.299974 0.150114)
			(end -0.299974 0.150114)
			(stroke
				(width 0.1)
				(type default)
			)
			(layer "F.Fab")
		)
		(fp_line
			(start -0.299974 -0.150114)
			(end 0.299974 -0.150114)
			(stroke
				(width 0.1)
				(type default)
			)
			(layer "F.Fab")
		)
		(fp_line
			(start 0.299974 -0.150114)
			(end 0.299974 0.150114)
			(stroke
				(width 0.1)
				(type default)
			)
			(layer "F.Fab")
		)
		(pad "1" smd rect
			(at -0.2667 0 270)
			(size 0.3048 0.381)
			(layers "F.Cu" "F.Mask" "F.Paste")
			(net "P5E_CPU1_P1_TX_C_DP<12>")
		)
		(pad "2" smd rect
			(at 0.2667 0 270)
			(size 0.3048 0.381)
			(layers "F.Cu" "F.Mask" "F.Paste")
			(net "P5E_CPU1_P1_TX_DP<12>")
		)
	)
	(footprint ""
		(layer "F.Cu")
		(at 76.250546 -394.903452 90)
		(property "Reference" "R732"
			(at 0 0 90)
			(layer "F.SilkS")
			(hide yes)
			(effects
				(font
					(size 1.27 1.27)
				)
			)
		)
		(property "Value" ""
			(at 0 0 90)
			(layer "F.Fab")
			(effects
				(font
					(size 1.27 1.27)
				)
			)
		)
		(duplicate_pad_numbers_are_jumpers no)
		(fp_line
			(start 0.32512 -0.175006)
			(end 0.32512 0.175006)
			(stroke
				(width 0.1)
				(type default)
			)
			(layer "F.Fab")
		)
		(fp_line
			(start -0.32512 -0.175006)
			(end 0.32512 -0.175006)
			(stroke
				(width 0.1)
				(type default)
			)
			(layer "F.Fab")
		)
		(fp_line
			(start 0.32512 0.175006)
			(end -0.32512 0.175006)
			(stroke
				(width 0.1)
				(type default)
			)
			(layer "F.Fab")
		)
		(fp_line
			(start -0.32512 0.175006)
			(end -0.32512 -0.175006)
			(stroke
				(width 0.1)
				(type default)
			)
			(layer "F.Fab")
		)
		(pad "1" smd rect
			(at -0.2667 0 90)
			(size 0.3048 0.381)
			(layers "F.Cu" "F.Mask" "F.Paste")
			(net "RST_RT_CPU1_P1_RESET_N")
		)
		(pad "2" smd rect
			(at 0.2667 0 270)
			(size 0.3048 0.381)
			(layers "F.Cu" "F.Mask" "F.Paste")
			(net "RST_RT_CPU1_P1_RESET_R_N")
		)
	)
	(footprint ""
		(layer "F.Cu")
		(at 442.340238 -364.49127)
		(property "Reference" "PC6003"
			(at 0 0 0)
			(layer "F.SilkS")
			(hide yes)
			(effects
				(font
					(size 1.27 1.27)
				)
			)
		)
		(property "Value" ""
			(at 0 0 0)
			(layer "F.Fab")
			(effects
				(font
					(size 1.27 1.27)
				)
			)
		)
		(duplicate_pad_numbers_are_jumpers no)
		(fp_line
			(start -0.7874 -0.4064)
			(end 0.7874 -0.4064)
			(stroke
				(width 0.1524)
				(type default)
			)
			(layer "F.SilkS")
		)
		(fp_line
			(start -0.7874 0.4064)
			(end -0.7874 -0.4064)
			(stroke
				(width 0.1524)
				(type default)
			)
			(layer "F.SilkS")
		)
		(fp_line
			(start 0.7874 -0.4064)
			(end 0.7874 0.4064)
			(stroke
				(width 0.1524)
				(type default)
			)
			(layer "F.SilkS")
		)
		(fp_line
			(start 0.7874 0.4064)
			(end -0.7874 0.4064)
			(stroke
				(width 0.1524)
				(type default)
			)
			(layer "F.SilkS")
		)
		(fp_line
			(start -0.67945 -0.305054)
			(end -0.12065 -0.305054)
			(stroke
				(width 0.1)
				(type default)
			)
			(layer "F.Fab")
		)
		(fp_line
			(start -0.67945 0.3048)
			(end -0.67945 -0.305054)
			(stroke
				(width 0.1)
				(type default)
			)
			(layer "F.Fab")
		)
		(fp_line
			(start -0.12065 -0.305054)
			(end -0.12065 -0.2794)
			(stroke
				(width 0.1)
				(type default)
			)
			(layer "F.Fab")
		)
		(fp_line
			(start -0.12065 -0.2794)
			(end 0.12065 -0.2794)
			(stroke
				(width 0.1)
				(type default)
			)
			(layer "F.Fab")
		)
		(fp_line
			(start -0.12065 0.2794)
			(end -0.12065 0.3048)
			(stroke
				(width 0.1)
				(type default)
			)
			(layer "F.Fab")
		)
		(fp_line
			(start -0.12065 0.3048)
			(end -0.67945 0.3048)
			(stroke
				(width 0.1)
				(type default)
			)
			(layer "F.Fab")
		)
		(fp_line
			(start 0.120396 0.2794)
			(end -0.12065 0.2794)
			(stroke
				(width 0.1)
				(type default)
			)
			(layer "F.Fab")
		)
		(fp_line
			(start 0.120396 0.3048)
			(end 0.120396 0.2794)
			(stroke
				(width 0.1)
				(type default)
			)
			(layer "F.Fab")
		)
		(fp_line
			(start 0.12065 -0.3048)
			(end 0.67945 -0.3048)
			(stroke
				(width 0.1)
				(type default)
			)
			(layer "F.Fab")
		)
		(fp_line
			(start 0.12065 -0.2794)
			(end 0.12065 -0.3048)
			(stroke
				(width 0.1)
				(type default)
			)
			(layer "F.Fab")
		)
		(fp_line
			(start 0.67945 -0.3048)
			(end 0.67945 0.3048)
			(stroke
				(width 0.1)
				(type default)
			)
			(layer "F.Fab")
		)
		(fp_line
			(start 0.67945 0.3048)
			(end 0.120396 0.3048)
			(stroke
				(width 0.1)
				(type default)
			)
			(layer "F.Fab")
		)
		(pad "1" smd circle
			(at -0.40005 0)
			(size 0 0)
			(layers "F.Cu" "F.Mask" "F.Paste")
			(net "P12V_AUX")
		)
		(pad "2" smd circle
			(at 0.40005 0)
			(size 0 0)
			(layers "F.Cu" "F.Mask" "F.Paste")
			(net "GND")
		)
	)
)
